# T6G (Grand Teton) — schematic netlist excerpt (pin names and nets, part order shuffled) for the footprints in the layout excerpt that follows; sources: Cadence DE-HDL packaged netlist, KiCad conversion of 04192023_DAF0TMB3IC0_F0TG_MB_C_brd_V02_OCP.brd

PR319  Q_RES  2.2 1% CHIP  pkg 0402LF  page 194 : A = PVDDCR_CPU0_P0_PVCC ; B = PVDDCR_CPU0_P0_VCC2
R294  Q_RES  1K 1% CHIP  pkg 0402LF  page 89 : A = PWRGD_CHD_CPU0_DIMM ; B = PWRGD_CHAF_CPU0
PC266_1  Q_CAP  22UF 16V 20% X6S  pkg C0805  page 211 : A = SW_P12V_AUX_PVDDCR_CPU0_P1_FLT ; B = GND

(kicad_pcb
	(version 20260206)
	(generator "pcbnew")
	(generator_version "10.0")
	(general
		(thickness 1.6)
		(legacy_teardrops no)
	)
	(paper "A4")
	(title_block
		(title "04192023_DAF0TMB3IC0_F0TG_MB_C_brd_V02_OCP.brd")
		(comment 1 "Grand Teton / footprints 5251-5253 of 8354")
	)
	(layers
		(0 "F.Cu" signal "TOP")
		(4 "In1.Cu" signal "GND")
		(6 "In2.Cu" signal "IN1")
		(8 "In3.Cu" signal "GND1")
		(10 "In4.Cu" signal "IN2")
		(12 "In5.Cu" signal "GND2")
		(14 "In6.Cu" signal "IN3")
		(16 "In7.Cu" signal "GND3")
		(18 "In8.Cu" signal "VCC")
		(20 "In9.Cu" signal "VCC1")
		(22 "In10.Cu" signal "GND4")
		(24 "In11.Cu" signal "IN4")
		(26 "In12.Cu" signal "GND5")
		(28 "In13.Cu" signal "IN5")
		(30 "In14.Cu" signal "GND6")
		(32 "In15.Cu" signal "IN6")
		(34 "In16.Cu" signal "GND7")
		(2 "B.Cu" signal "BOTTOM")
		(9 "F.Adhes" user "F.Adhesive")
		(11 "B.Adhes" user "B.Adhesive")
		(13 "F.Paste" user "Package Geometry/Pastemask Top")
		(15 "B.Paste" user "Package Geometry/Pastemask Bottom")
		(5 "F.SilkS" user "Ref Des/Silkscreen Top")
		(7 "B.SilkS" user "Ref Des/Silkscreen Bottom")
		(1 "F.Mask" user "Board Geometry/Soldermask Top")
		(3 "B.Mask" user "Board Geometry/Soldermask Bottom")
		(17 "Dwgs.User" user "User.Drawings")
		(19 "Cmts.User" user "User.Comments")
		(21 "Eco1.User" user "User.Eco1")
		(23 "Eco2.User" user "User.Eco2")
		(25 "Edge.Cuts" user "Board Geometry/Outline")
		(27 "Margin" user)
		(31 "F.CrtYd" user "Package Geometry/Place Bound Top")
		(29 "B.CrtYd" user "Package Geometry/Place Bound Bottom")
		(35 "F.Fab" user "Ref Des/Assembly Top")
		(33 "B.Fab" user "Ref Des/Assembly Bottom")
	)
	(footprint ""
		(layer "B.Cu")
		(at 280.492454 -190.94831 180)
		(property "Reference" "R294"
			(at 0 0 0)
			(layer "B.SilkS")
			(hide yes)
			(effects
				(font
					(size 1.27 1.27)
				)
				(justify mirror)
			)
		)
		(property "Value" ""
			(at 0 0 0)
			(layer "B.Fab")
			(effects
				(font
					(size 1.27 1.27)
				)
				(justify mirror)
			)
		)
		(duplicate_pad_numbers_are_jumpers no)
		(fp_line
			(start 0.7874 0.4064)
			(end 0.7874 -0.4064)
			(stroke
				(width 0.1524)
				(type default)
			)
			(layer "B.SilkS")
		)
		(fp_line
			(start 0.7874 -0.4064)
			(end -0.7874 -0.4064)
			(stroke
				(width 0.1524)
				(type default)
			)
			(layer "B.SilkS")
		)
		(fp_line
			(start -0.7874 0.4064)
			(end 0.7874 0.4064)
			(stroke
				(width 0.1524)
				(type default)
			)
			(layer "B.SilkS")
		)
		(fp_line
			(start -0.7874 -0.4064)
			(end -0.7874 0.4064)
			(stroke
				(width 0.1524)
				(type default)
			)
			(layer "B.SilkS")
		)
		(fp_line
			(start 0.67945 0.3048)
			(end 0.67945 -0.305054)
			(stroke
				(width 0.1)
				(type default)
			)
			(layer "B.Fab")
		)
		(fp_line
			(start 0.67945 -0.305054)
			(end 0.12065 -0.305054)
			(stroke
				(width 0.1)
				(type default)
			)
			(layer "B.Fab")
		)
		(fp_line
			(start 0.12065 0.3048)
			(end 0.67945 0.3048)
			(stroke
				(width 0.1)
				(type default)
			)
			(layer "B.Fab")
		)
		(fp_line
			(start 0.12065 0.2794)
			(end 0.12065 0.3048)
			(stroke
				(width 0.1)
				(type default)
			)
			(layer "B.Fab")
		)
		(fp_line
			(start 0.12065 -0.2794)
			(end -0.12065 -0.2794)
			(stroke
				(width 0.1)
				(type default)
			)
			(layer "B.Fab")
		)
		(fp_line
			(start 0.12065 -0.305054)
			(end 0.12065 -0.2794)
			(stroke
				(width 0.1)
				(type default)
			)
			(layer "B.Fab")
		)
		(fp_line
			(start -0.120396 0.3048)
			(end -0.120396 0.2794)
			(stroke
				(width 0.1)
				(type default)
			)
			(layer "B.Fab")
		)
		(fp_line
			(start -0.120396 0.2794)
			(end 0.12065 0.2794)
			(stroke
				(width 0.1)
				(type default)
			)
			(layer "B.Fab")
		)
		(fp_line
			(start -0.12065 -0.2794)
			(end -0.12065 -0.3048)
			(stroke
				(width 0.1)
				(type default)
			)
			(layer "B.Fab")
		)
		(fp_line
			(start -0.12065 -0.3048)
			(end -0.67945 -0.3048)
			(stroke
				(width 0.1)
				(type default)
			)
			(layer "B.Fab")
		)
		(fp_line
			(start -0.67945 0.3048)
			(end -0.120396 0.3048)
			(stroke
				(width 0.1)
				(type default)
			)
			(layer "B.Fab")
		)
		(fp_line
			(start -0.67945 -0.3048)
			(end -0.67945 0.3048)
			(stroke
				(width 0.1)
				(type default)
			)
			(layer "B.Fab")
		)
		(pad "1" smd circle
			(at 0.40005 0)
			(size 0 0)
			(layers "B.Cu" "B.Mask" "B.Paste")
			(net "PWRGD_CHD_CPU0_DIMM")
		)
		(pad "2" smd circle
			(at -0.40005 0)
			(size 0 0)
			(layers "B.Cu" "B.Mask" "B.Paste")
			(net "PWRGD_CHAF_CPU0")
		)
	)
	(footprint ""
		(layer "B.Cu")
		(at 81.257648 -182.656734 -90)
		(property "Reference" "PC266_1"
			(at 0 0 90)
			(layer "B.SilkS")
			(hide yes)
			(effects
				(font
					(size 1.27 1.27)
				)
				(justify mirror)
			)
		)
		(property "Value" ""
			(at 0 0 90)
			(layer "B.Fab")
			(effects
				(font
					(size 1.27 1.27)
				)
				(justify mirror)
			)
		)
		(duplicate_pad_numbers_are_jumpers no)
		(fp_line
			(start -1.524 0.762)
			(end 1.524 0.762)
			(stroke
				(width 0.1524)
				(type default)
			)
			(layer "B.SilkS")
		)
		(fp_line
			(start 1.524 0.762)
			(end 1.524 -0.762)
			(stroke
				(width 0.1524)
				(type default)
			)
			(layer "B.SilkS")
		)
		(fp_line
			(start -1.524 -0.762)
			(end -1.524 0.762)
			(stroke
				(width 0.1524)
				(type default)
			)
			(layer "B.SilkS")
		)
		(fp_line
			(start 1.524 -0.762)
			(end -1.524 -0.762)
			(stroke
				(width 0.1524)
				(type default)
			)
			(layer "B.SilkS")
		)
		(fp_line
			(start -1.1049 0.724916)
			(end -1.1049 -0.724916)
			(stroke
				(width 0.1)
				(type default)
			)
			(layer "B.Fab")
		)
		(fp_line
			(start 1.1049 0.724916)
			(end -1.1049 0.724916)
			(stroke
				(width 0.1)
				(type default)
			)
			(layer "B.Fab")
		)
		(fp_line
			(start -1.1049 -0.724916)
			(end 1.1049 -0.724916)
			(stroke
				(width 0.1)
				(type default)
			)
			(layer "B.Fab")
		)
		(fp_line
			(start 1.1049 -0.724916)
			(end 1.1049 0.724916)
			(stroke
				(width 0.1)
				(type default)
			)
			(layer "B.Fab")
		)
		(pad "1" smd rect
			(at 0.889 0 270)
			(size 1.016 1.27)
			(layers "B.Cu" "B.Mask" "B.Paste")
			(net "SW_P12V_AUX_PVDDCR_CPU0_P1_FLT")
		)
		(pad "2" smd rect
			(at -0.889 0 270)
			(size 1.016 1.27)
			(layers "B.Cu" "B.Mask" "B.Paste")
			(net "GND")
		)
	)
	(footprint ""
		(layer "B.Cu")
		(at 374.986042 -181.684676 90)
		(property "Reference" "PR319"
			(at 0 0 90)
			(layer "B.SilkS")
			(hide yes)
			(effects
				(font
					(size 1.27 1.27)
				)
				(justify mirror)
			)
		)
		(property "Value" ""
			(at 0 0 90)
			(layer "B.Fab")
			(effects
				(font
					(size 1.27 1.27)
				)
				(justify mirror)
			)
		)
		(duplicate_pad_numbers_are_jumpers no)
		(fp_line
			(start 0.7874 -0.4064)
			(end -0.7874 -0.4064)
			(stroke
				(width 0.1524)
				(type default)
			)
			(layer "B.SilkS")
		)
		(fp_line
			(start -0.7874 -0.4064)
			(end -0.7874 0.4064)
			(stroke
				(width 0.1524)
				(type default)
			)
			(layer "B.SilkS")
		)
		(fp_line
			(start 0.7874 0.4064)
			(end 0.7874 -0.4064)
			(stroke
				(width 0.1524)
				(type default)
			)
			(layer "B.SilkS")
		)
		(fp_line
			(start -0.7874 0.4064)
			(end 0.7874 0.4064)
			(stroke
				(width 0.1524)
				(type default)
			)
			(layer "B.SilkS")
		)
		(fp_line
			(start 0.67945 -0.305054)
			(end 0.12065 -0.305054)
			(stroke
				(width 0.1)
				(type default)
			)
			(layer "B.Fab")
		)
		(fp_line
			(start 0.12065 -0.305054)
			(end 0.12065 -0.2794)
			(stroke
				(width 0.1)
				(type default)
			)
			(layer "B.Fab")
		)
		(fp_line
			(start -0.12065 -0.3048)
			(end -0.67945 -0.3048)
			(stroke
				(width 0.1)
				(type default)
			)
			(layer "B.Fab")
		)
		(fp_line
			(start -0.67945 -0.3048)
			(end -0.67945 0.3048)
			(stroke
				(width 0.1)
				(type default)
			)
			(layer "B.Fab")
		)
		(fp_line
			(start 0.12065 -0.2794)
			(end -0.12065 -0.2794)
			(stroke
				(width 0.1)
				(type default)
			)
			(layer "B.Fab")
		)
		(fp_line
			(start -0.12065 -0.2794)
			(end -0.12065 -0.3048)
			(stroke
				(width 0.1)
				(type default)
			)
			(layer "B.Fab")
		)
		(fp_line
			(start 0.12065 0.2794)
			(end 0.12065 0.3048)
			(stroke
				(width 0.1)
				(type default)
			)
			(layer "B.Fab")
		)
		(fp_line
			(start -0.120396 0.2794)
			(end 0.12065 0.2794)
			(stroke
				(width 0.1)
				(type default)
			)
			(layer "B.Fab")
		)
		(fp_line
			(start 0.67945 0.3048)
			(end 0.67945 -0.305054)
			(stroke
				(width 0.1)
				(type default)
			)
			(layer "B.Fab")
		)
		(fp_line
			(start 0.12065 0.3048)
			(end 0.67945 0.3048)
			(stroke
				(width 0.1)
				(type default)
			)
			(layer "B.Fab")
		)
		(fp_line
			(start -0.120396 0.3048)
			(end -0.120396 0.2794)
			(stroke
				(width 0.1)
				(type default)
			)
			(layer "B.Fab")
		)
		(fp_line
			(start -0.67945 0.3048)
			(end -0.120396 0.3048)
			(stroke
				(width 0.1)
				(type default)
			)
			(layer "B.Fab")
		)
		(pad "1" smd circle
			(at 0.40005 0 270)
			(size 0 0)
			(layers "B.Cu" "B.Mask" "B.Paste")
			(net "PVDDCR_CPU0_P0_PVCC")
		)
		(pad "2" smd circle
			(at -0.40005 0 270)
			(size 0 0)
			(layers "B.Cu" "B.Mask" "B.Paste")
			(net "PVDDCR_CPU0_P0_VCC2")
		)
	)
)
